(kicad_pcb
	(version 20260206)
	(generator "pcbnew")
	(generator_version "10.0")
	(general
		(thickness 1.6)
		(legacy_teardrops no)
	)
	(paper "A4")
	(title_block
		(title "peb — Lightning_PEB_BRD.brd")
		(comment 1 "Lightning (Wiwynn / Facebook NVMe JBOF) / footprints 349-357 of 2563")
	)
	(layers
		(0 "F.Cu" signal "TOP")
		(4 "In1.Cu" signal "L2GND")
		(6 "In2.Cu" signal "L3")
		(8 "In3.Cu" signal "L4VCC")
		(10 "In4.Cu" signal "L5VCC")
		(12 "In5.Cu" signal "L6")
		(14 "In6.Cu" signal "L7GND")
		(2 "B.Cu" signal "BOTTOM")
		(9 "F.Adhes" user "F.Adhesive")
		(11 "B.Adhes" user "B.Adhesive")
		(13 "F.Paste" user "Package Geometry/Pastemask Top")
		(15 "B.Paste" user "Package Geometry/Pastemask Bottom")
		(5 "F.SilkS" user "Ref Des/Silkscreen Top")
		(7 "B.SilkS" user "Ref Des/Silkscreen Bottom")
		(1 "F.Mask" user "Board Geometry/Soldermask Top")
		(3 "B.Mask" user "Board Geometry/Soldermask Bottom")
		(17 "Dwgs.User" user "User.Drawings")
		(19 "Cmts.User" user "User.Comments")
		(21 "Eco1.User" user "User.Eco1")
		(23 "Eco2.User" user "User.Eco2")
		(25 "Edge.Cuts" user "Board Geometry/Outline")
		(27 "Margin" user)
		(31 "F.CrtYd" user "Package Geometry/Place Bound Top")
		(29 "B.CrtYd" user "Package Geometry/Place Bound Bottom")
		(35 "F.Fab" user "Ref Des/Assembly Top")
		(33 "B.Fab" user "Ref Des/Assembly Bottom")
	)
	(footprint ""
		(layer "F.Cu")
		(at 153.4922 -33.5026)
		(property "Reference" "C395"
			(at 0 0 0)
			(layer "F.SilkS")
			(hide yes)
			(effects
				(font
					(size 1.27 1.27)
				)
			)
		)
		(property "Value" "SCD22U10V2KX-1GP"
			(at 1.1811 -2.7051 0)
			(unlocked yes)
			(layer "F.Fab")
			(hide yes)
			(effects
				(font
					(size 1.016 1.016)
					(thickness 0.1524)
				)
			)
		)
		(property "Device Type" "C402H22"
			(at 1.1811 -4.2291 0)
			(unlocked yes)
			(layer "F.Fab")
			(hide yes)
			(effects
				(font
					(size 1.016 1.016)
					(thickness 0.1524)
				)
			)
		)
		(duplicate_pad_numbers_are_jumpers no)
		(fp_rect
			(start -0.4318 0.9525)
			(end 0.4318 -0.9525)
			(stroke
				(width 0)
				(type default)
			)
			(fill no)
			(layer "F.CrtYd")
		)
		(fp_rect
			(start -0.4318 0.9525)
			(end 0.4318 -0.9525)
			(stroke
				(width 0)
				(type default)
			)
			(fill no)
			(layer "F.Fab")
		)
		(pad "1" smd custom
			(at 0 -0.4445)
			(size 0.1524 0.1524)
			(layers "F.Cu" "F.Mask" "F.Paste")
			(net "PCIE_TX_CAP_N87")
			(options
				(clearance outline)
				(anchor circle)
			)
			(primitives
				(gr_poly
					(pts
						(arc
							(start 0.3048 -0.2032)
							(mid 0.275042 -0.275042)
							(end 0.2032 -0.3048)
						)
						(arc
							(start -0.2032 -0.3048)
							(mid -0.275042 -0.275042)
							(end -0.3048 -0.2032)
						)
						(arc
							(start -0.3048 0.2032)
							(mid -0.275042 0.275042)
							(end -0.2032 0.3048)
						)
						(arc
							(start 0.2032 0.3048)
							(mid 0.275042 0.275042)
							(end 0.3048 0.2032)
						)
					)
					(width 0)
					(fill yes)
				)
			)
		)
		(pad "2" smd custom
			(at 0 0.4445)
			(size 0.1524 0.1524)
			(layers "F.Cu" "F.Mask" "F.Paste")
			(net "PCIE_TX_N87")
			(options
				(clearance outline)
				(anchor circle)
			)
			(primitives
				(gr_poly
					(pts
						(arc
							(start 0.3048 -0.2032)
							(mid 0.275042 -0.275042)
							(end 0.2032 -0.3048)
						)
						(arc
							(start -0.2032 -0.3048)
							(mid -0.275042 -0.275042)
							(end -0.3048 -0.2032)
						)
						(arc
							(start -0.3048 0.2032)
							(mid -0.275042 0.275042)
							(end -0.2032 0.3048)
						)
						(arc
							(start 0.2032 0.3048)
							(mid 0.275042 0.275042)
							(end 0.3048 0.2032)
						)
					)
					(width 0)
					(fill yes)
				)
			)
		)
	)
	(footprint ""
		(layer "F.Cu")
		(at 22.479 -163.068 -90)
		(property "Reference" "R505"
			(at 0 0 270)
			(layer "F.SilkS")
			(hide yes)
			(effects
				(font
					(size 1.27 1.27)
				)
			)
		)
		(property "Value" "4K7R2F-GP"
			(at 0.064008 -3.993896 270)
			(unlocked yes)
			(layer "F.Fab")
			(hide yes)
			(effects
				(font
					(size 1.016 1.016)
					(thickness 0.1524)
				)
			)
		)
		(property "Device Type" "R402H16"
			(at 0.064008 -5.517896 270)
			(unlocked yes)
			(layer "F.Fab")
			(hide yes)
			(effects
				(font
					(size 1.016 1.016)
					(thickness 0.1524)
				)
			)
		)
		(duplicate_pad_numbers_are_jumpers no)
		(fp_line
			(start -0.508 -0.9398)
			(end -0.508 0.9398)
			(stroke
				(width 0.1524)
				(type default)
			)
			(layer "F.SilkS")
		)
		(fp_line
			(start 0.508 -0.9398)
			(end -0.508 -0.9398)
			(stroke
				(width 0.1524)
				(type default)
			)
			(layer "F.SilkS")
		)
		(fp_rect
			(start -0.508 0.9398)
			(end 0.508 -0.9398)
			(stroke
				(width 0)
				(type default)
			)
			(fill no)
			(layer "F.CrtYd")
		)
		(fp_rect
			(start -0.508 0.9398)
			(end 0.508 -0.9398)
			(stroke
				(width 0)
				(type default)
			)
			(fill no)
			(layer "F.Fab")
		)
		(pad "1" smd custom
			(at 0 -0.4445 270)
			(size 0.1397 0.1397)
			(layers "F.Cu" "F.Mask" "F.Paste")
			(net "BMC_RESET#_DDR3")
			(options
				(clearance outline)
				(anchor circle)
			)
			(primitives
				(gr_poly
					(pts
						(arc
							(start -0.1778 -0.2794)
							(mid -0.249642 -0.249642)
							(end -0.2794 -0.1778)
						)
						(arc
							(start -0.2794 0.1778)
							(mid -0.249642 0.249642)
							(end -0.1778 0.2794)
						)
						(arc
							(start 0.1778 0.2794)
							(mid 0.249642 0.249642)
							(end 0.2794 0.1778)
						)
						(arc
							(start 0.2794 -0.1778)
							(mid 0.249642 -0.249642)
							(end 0.1778 -0.2794)
						)
					)
					(width 0)
					(fill yes)
				)
			)
		)
		(pad "2" smd custom
			(at 0 0.4445 270)
			(size 0.1397 0.1397)
			(layers "F.Cu" "F.Mask" "F.Paste")
			(net "P3V3_STBY")
			(options
				(clearance outline)
				(anchor circle)
			)
			(primitives
				(gr_poly
					(pts
						(arc
							(start -0.1778 -0.2794)
							(mid -0.249642 -0.249642)
							(end -0.2794 -0.1778)
						)
						(arc
							(start -0.2794 0.1778)
							(mid -0.249642 0.249642)
							(end -0.1778 0.2794)
						)
						(arc
							(start 0.1778 0.2794)
							(mid 0.249642 0.249642)
							(end 0.2794 0.1778)
						)
						(arc
							(start 0.2794 -0.1778)
							(mid 0.249642 -0.249642)
							(end 0.1778 -0.2794)
						)
					)
					(width 0)
					(fill yes)
				)
			)
		)
	)
	(footprint ""
		(layer "F.Cu")
		(at 34.429954 -163.559744 90)
		(property "Reference" "C177"
			(at 0 0 90)
			(layer "F.SilkS")
			(hide yes)
			(effects
				(font
					(size 1.27 1.27)
				)
			)
		)
		(property "Value" "SCD01U25V2KX-3GP"
			(at 1.1811 -2.7051 90)
			(unlocked yes)
			(layer "F.Fab")
			(hide yes)
			(effects
				(font
					(size 1.016 1.016)
					(thickness 0.1524)
				)
			)
		)
		(property "Device Type" "C402H22"
			(at 1.1811 -4.2291 90)
			(unlocked yes)
			(layer "F.Fab")
			(hide yes)
			(effects
				(font
					(size 1.016 1.016)
					(thickness 0.1524)
				)
			)
		)
		(duplicate_pad_numbers_are_jumpers no)
		(fp_rect
			(start -0.4318 0.9525)
			(end 0.4318 -0.9525)
			(stroke
				(width 0)
				(type default)
			)
			(fill no)
			(layer "F.CrtYd")
		)
		(fp_rect
			(start -0.4318 0.9525)
			(end 0.4318 -0.9525)
			(stroke
				(width 0)
				(type default)
			)
			(fill no)
			(layer "F.Fab")
		)
		(pad "1" smd custom
			(at 0 -0.4445 90)
			(size 0.1524 0.1524)
			(layers "F.Cu" "F.Mask" "F.Paste")
			(net "P1V53_STBY")
			(options
				(clearance outline)
				(anchor circle)
			)
			(primitives
				(gr_poly
					(pts
						(arc
							(start 0.3048 -0.2032)
							(mid 0.275042 -0.275042)
							(end 0.2032 -0.3048)
						)
						(arc
							(start -0.2032 -0.3048)
							(mid -0.275042 -0.275042)
							(end -0.3048 -0.2032)
						)
						(arc
							(start -0.3048 0.2032)
							(mid -0.275042 0.275042)
							(end -0.2032 0.3048)
						)
						(arc
							(start 0.2032 0.3048)
							(mid 0.275042 0.275042)
							(end 0.3048 0.2032)
						)
					)
					(width 0)
					(fill yes)
				)
			)
		)
		(pad "2" smd custom
			(at 0 0.4445 90)
			(size 0.1524 0.1524)
			(layers "F.Cu" "F.Mask" "F.Paste")
			(net "DDR_VREF")
			(options
				(clearance outline)
				(anchor circle)
			)
			(primitives
				(gr_poly
					(pts
						(arc
							(start 0.3048 -0.2032)
							(mid 0.275042 -0.275042)
							(end 0.2032 -0.3048)
						)
						(arc
							(start -0.2032 -0.3048)
							(mid -0.275042 -0.275042)
							(end -0.3048 -0.2032)
						)
						(arc
							(start -0.3048 0.2032)
							(mid -0.275042 0.275042)
							(end -0.2032 0.3048)
						)
						(arc
							(start 0.2032 0.3048)
							(mid 0.275042 0.275042)
							(end 0.3048 0.2032)
						)
					)
					(width 0)
					(fill yes)
				)
			)
		)
	)
	(footprint ""
		(layer "F.Cu")
		(at 14.351 -94.7166 90)
		(property "Reference" "TP134"
			(at 0 0 90)
			(layer "F.SilkS")
			(hide yes)
			(effects
				(font
					(size 1.27 1.27)
				)
			)
		)
		(property "Value" "TPAD28-2-GP"
			(at -0.0127 -1.6637 90)
			(unlocked yes)
			(layer "F.Fab")
			(hide yes)
			(effects
				(font
					(size 1.016 1.016)
					(thickness 0.1524)
				)
			)
		)
		(property "Device Type" "TPAD28"
			(at -0.0127 -3.1877 90)
			(unlocked yes)
			(layer "F.Fab")
			(hide yes)
			(effects
				(font
					(size 1.016 1.016)
					(thickness 0.1524)
				)
			)
		)
		(duplicate_pad_numbers_are_jumpers no)
		(fp_poly
			(pts
				(arc
					(start 0 0.3556)
					(mid 0 -0.3556)
					(end 0 0.3556)
				)
			)
			(stroke
				(width 0)
				(type default)
			)
			(fill no)
			(layer "F.CrtYd")
		)
		(fp_poly
			(pts
				(arc
					(start 0 0.6096)
					(mid 0 -0.6096)
					(end 0 0.6096)
				)
			)
			(stroke
				(width 0)
				(type default)
			)
			(fill no)
			(layer "F.Fab")
		)
		(pad "1" smd circle
			(at 0 0 90)
			(size 0.7112 0.7112)
			(layers "F.Cu" "F.Mask" "F.Paste")
			(net "NCSI_10G_RCLK")
		)
	)
	(footprint ""
		(layer "F.Cu")
		(at 21.336 -143.383)
		(property "Reference" "C203"
			(at 0 0 0)
			(layer "F.SilkS")
			(hide yes)
			(effects
				(font
					(size 1.27 1.27)
				)
			)
		)
		(property "Value" "SC100P50V2JN-3GP"
			(at 1.1811 -2.7051 0)
			(unlocked yes)
			(layer "F.Fab")
			(hide yes)
			(effects
				(font
					(size 1.016 1.016)
					(thickness 0.1524)
				)
			)
		)
		(property "Device Type" "C402H22"
			(at 1.1811 -4.2291 0)
			(unlocked yes)
			(layer "F.Fab")
			(hide yes)
			(effects
				(font
					(size 1.016 1.016)
					(thickness 0.1524)
				)
			)
		)
		(duplicate_pad_numbers_are_jumpers no)
		(fp_rect
			(start -0.4318 0.9525)
			(end 0.4318 -0.9525)
			(stroke
				(width 0)
				(type default)
			)
			(fill no)
			(layer "F.CrtYd")
		)
		(fp_rect
			(start -0.4318 0.9525)
			(end 0.4318 -0.9525)
			(stroke
				(width 0)
				(type default)
			)
			(fill no)
			(layer "F.Fab")
		)
		(pad "1" smd custom
			(at 0 -0.4445)
			(size 0.1524 0.1524)
			(layers "F.Cu" "F.Mask" "F.Paste")
			(net "V1PLLAV12")
			(options
				(clearance outline)
				(anchor circle)
			)
			(primitives
				(gr_poly
					(pts
						(arc
							(start 0.3048 -0.2032)
							(mid 0.275042 -0.275042)
							(end 0.2032 -0.3048)
						)
						(arc
							(start -0.2032 -0.3048)
							(mid -0.275042 -0.275042)
							(end -0.3048 -0.2032)
						)
						(arc
							(start -0.3048 0.2032)
							(mid -0.275042 0.275042)
							(end -0.2032 0.3048)
						)
						(arc
							(start 0.2032 0.3048)
							(mid 0.275042 0.275042)
							(end 0.3048 0.2032)
						)
					)
					(width 0)
					(fill yes)
				)
			)
		)
		(pad "2" smd custom
			(at 0 0.4445)
			(size 0.1524 0.1524)
			(layers "F.Cu" "F.Mask" "F.Paste")
			(net "GND")
			(options
				(clearance outline)
				(anchor circle)
			)
			(primitives
				(gr_poly
					(pts
						(arc
							(start 0.3048 -0.2032)
							(mid 0.275042 -0.275042)
							(end 0.2032 -0.3048)
						)
						(arc
							(start -0.2032 -0.3048)
							(mid -0.275042 -0.275042)
							(end -0.3048 -0.2032)
						)
						(arc
							(start -0.3048 0.2032)
							(mid -0.275042 0.275042)
							(end -0.2032 0.3048)
						)
						(arc
							(start 0.2032 0.3048)
							(mid 0.275042 0.275042)
							(end 0.3048 0.2032)
						)
					)
					(width 0)
					(fill yes)
				)
			)
		)
	)
	(footprint ""
		(layer "F.Cu")
		(at 23.1902 -84.2264 -90)
		(property "Reference" "TP158"
			(at 0 0 270)
			(layer "F.SilkS")
			(hide yes)
			(effects
				(font
					(size 1.27 1.27)
				)
			)
		)
		(property "Value" "TPAD28-2-GP"
			(at -0.0127 -1.6637 270)
			(unlocked yes)
			(layer "F.Fab")
			(hide yes)
			(effects
				(font
					(size 1.016 1.016)
					(thickness 0.1524)
				)
			)
		)
		(property "Device Type" "TPAD28"
			(at -0.0127 -3.1877 270)
			(unlocked yes)
			(layer "F.Fab")
			(hide yes)
			(effects
				(font
					(size 1.016 1.016)
					(thickness 0.1524)
				)
			)
		)
		(duplicate_pad_numbers_are_jumpers no)
		(fp_poly
			(pts
				(arc
					(start 0 -0.3556)
					(mid 0 0.3556)
					(end 0 -0.3556)
				)
			)
			(stroke
				(width 0)
				(type default)
			)
			(fill no)
			(layer "F.CrtYd")
		)
		(fp_poly
			(pts
				(arc
					(start 0 -0.6096)
					(mid 0 0.6096)
					(end 0 -0.6096)
				)
			)
			(stroke
				(width 0)
				(type default)
			)
			(fill no)
			(layer "F.Fab")
		)
		(pad "1" smd circle
			(at 0 0 270)
			(size 0.7112 0.7112)
			(layers "F.Cu" "F.Mask" "F.Paste")
			(net "NIC_JTCK")
		)
	)
	(footprint ""
		(layer "F.Cu")
		(at 230.251 -11.43 90)
		(property "Reference" "C728"
			(at 0 0 90)
			(layer "F.SilkS")
			(hide yes)
			(effects
				(font
					(size 1.27 1.27)
				)
			)
		)
		(property "Value" "SCD01U25V2KX-3GP"
			(at 1.1811 -2.7051 90)
			(unlocked yes)
			(layer "F.Fab")
			(hide yes)
			(effects
				(font
					(size 1.016 1.016)
					(thickness 0.1524)
				)
			)
		)
		(property "Device Type" "C402H22"
			(at 1.1811 -4.2291 90)
			(unlocked yes)
			(layer "F.Fab")
			(hide yes)
			(effects
				(font
					(size 1.016 1.016)
					(thickness 0.1524)
				)
			)
		)
		(duplicate_pad_numbers_are_jumpers no)
		(fp_rect
			(start -0.4318 0.9525)
			(end 0.4318 -0.9525)
			(stroke
				(width 0)
				(type default)
			)
			(fill no)
			(layer "F.CrtYd")
		)
		(fp_rect
			(start -0.4318 0.9525)
			(end 0.4318 -0.9525)
			(stroke
				(width 0)
				(type default)
			)
			(fill no)
			(layer "F.Fab")
		)
		(pad "1" smd custom
			(at 0 -0.4445 90)
			(size 0.1524 0.1524)
			(layers "F.Cu" "F.Mask" "F.Paste")
			(net "P3V3_STBY")
			(options
				(clearance outline)
				(anchor circle)
			)
			(primitives
				(gr_poly
					(pts
						(arc
							(start 0.3048 -0.2032)
							(mid 0.275042 -0.275042)
							(end 0.2032 -0.3048)
						)
						(arc
							(start -0.2032 -0.3048)
							(mid -0.275042 -0.275042)
							(end -0.3048 -0.2032)
						)
						(arc
							(start -0.3048 0.2032)
							(mid -0.275042 0.275042)
							(end -0.2032 0.3048)
						)
						(arc
							(start 0.2032 0.3048)
							(mid 0.275042 0.275042)
							(end 0.3048 0.2032)
						)
					)
					(width 0)
					(fill yes)
				)
			)
		)
		(pad "2" smd custom
			(at 0 0.4445 90)
			(size 0.1524 0.1524)
			(layers "F.Cu" "F.Mask" "F.Paste")
			(net "GND")
			(options
				(clearance outline)
				(anchor circle)
			)
			(primitives
				(gr_poly
					(pts
						(arc
							(start 0.3048 -0.2032)
							(mid 0.275042 -0.275042)
							(end 0.2032 -0.3048)
						)
						(arc
							(start -0.2032 -0.3048)
							(mid -0.275042 -0.275042)
							(end -0.3048 -0.2032)
						)
						(arc
							(start -0.3048 0.2032)
							(mid -0.275042 0.275042)
							(end -0.2032 0.3048)
						)
						(arc
							(start 0.2032 0.3048)
							(mid 0.275042 0.275042)
							(end 0.3048 0.2032)
						)
					)
					(width 0)
					(fill yes)
				)
			)
		)
	)
	(footprint ""
		(layer "F.Cu")
		(at 58.166 -132.1054 180)
		(property "Reference" "R5769"
			(at 0 0 180)
			(layer "F.SilkS")
			(hide yes)
			(effects
				(font
					(size 1.27 1.27)
				)
			)
		)
		(property "Value" "1KR2F-3-GP"
			(at 0.064008 -3.993896 180)
			(unlocked yes)
			(layer "F.Fab")
			(hide yes)
			(effects
				(font
					(size 1.016 1.016)
					(thickness 0.1524)
				)
			)
		)
		(property "Device Type" "R402H16"
			(at 0.064008 -5.517896 180)
			(unlocked yes)
			(layer "F.Fab")
			(hide yes)
			(effects
				(font
					(size 1.016 1.016)
					(thickness 0.1524)
				)
			)
		)
		(duplicate_pad_numbers_are_jumpers no)
		(fp_line
			(start 0.508 -0.9398)
			(end -0.508 -0.9398)
			(stroke
				(width 0.1524)
				(type default)
			)
			(layer "F.SilkS")
		)
		(fp_line
			(start -0.508 -0.9398)
			(end -0.508 0.9398)
			(stroke
				(width 0.1524)
				(type default)
			)
			(layer "F.SilkS")
		)
		(fp_rect
			(start -0.508 0.9398)
			(end 0.508 -0.9398)
			(stroke
				(width 0)
				(type default)
			)
			(fill no)
			(layer "F.CrtYd")
		)
		(fp_rect
			(start -0.508 0.9398)
			(end 0.508 -0.9398)
			(stroke
				(width 0)
				(type default)
			)
			(fill no)
			(layer "F.Fab")
		)
		(pad "1" smd custom
			(at 0 -0.4445 180)
			(size 0.1397 0.1397)
			(layers "F.Cu" "F.Mask" "F.Paste")
			(net "P1V53_STBY")
			(options
				(clearance outline)
				(anchor circle)
			)
			(primitives
				(gr_poly
					(pts
						(arc
							(start -0.1778 -0.2794)
							(mid -0.249642 -0.249642)
							(end -0.2794 -0.1778)
						)
						(arc
							(start -0.2794 0.1778)
							(mid -0.249642 0.249642)
							(end -0.1778 0.2794)
						)
						(arc
							(start 0.1778 0.2794)
							(mid 0.249642 0.249642)
							(end 0.2794 0.1778)
						)
						(arc
							(start 0.2794 -0.1778)
							(mid 0.249642 -0.249642)
							(end 0.1778 -0.2794)
						)
					)
					(width 0)
					(fill yes)
				)
			)
		)
		(pad "2" smd custom
			(at 0 0.4445 180)
			(size 0.1397 0.1397)
			(layers "F.Cu" "F.Mask" "F.Paste")
			(net "ADC_P1V53V")
			(options
				(clearance outline)
				(anchor circle)
			)
			(primitives
				(gr_poly
					(pts
						(arc
							(start -0.1778 -0.2794)
							(mid -0.249642 -0.249642)
							(end -0.2794 -0.1778)
						)
						(arc
							(start -0.2794 0.1778)
							(mid -0.249642 0.249642)
							(end -0.1778 0.2794)
						)
						(arc
							(start 0.1778 0.2794)
							(mid 0.249642 0.249642)
							(end 0.2794 0.1778)
						)
						(arc
							(start 0.2794 -0.1778)
							(mid 0.249642 -0.249642)
							(end 0.1778 -0.2794)
						)
					)
					(width 0)
					(fill yes)
				)
			)
		)
	)
	(footprint ""
		(layer "F.Cu")
		(at 21.5646 -148.336 180)
		(property "Reference" "R3604"
			(at 0 0 180)
			(layer "F.SilkS")
			(hide yes)
			(effects
				(font
					(size 1.27 1.27)
				)
			)
		)
		(property "Value" "0R2J-2-GP"
			(at 0.064008 -3.993896 180)
			(unlocked yes)
			(layer "F.Fab")
			(hide yes)
			(effects
				(font
					(size 1.016 1.016)
					(thickness 0.1524)
				)
			)
		)
		(property "Device Type" "R402H16"
			(at 0.064008 -5.517896 180)
			(unlocked yes)
			(layer "F.Fab")
			(hide yes)
			(effects
				(font
					(size 1.016 1.016)
					(thickness 0.1524)
				)
			)
		)
		(duplicate_pad_numbers_are_jumpers no)
		(fp_line
			(start 0.508 -0.9398)
			(end -0.508 -0.9398)
			(stroke
				(width 0.1524)
				(type default)
			)
			(layer "F.SilkS")
		)
		(fp_line
			(start -0.508 -0.9398)
			(end -0.508 0.9398)
			(stroke
				(width 0.1524)
				(type default)
			)
			(layer "F.SilkS")
		)
		(fp_rect
			(start -0.508 0.9398)
			(end 0.508 -0.9398)
			(stroke
				(width 0)
				(type default)
			)
			(fill no)
			(layer "F.CrtYd")
		)
		(fp_rect
			(start -0.508 0.9398)
			(end 0.508 -0.9398)
			(stroke
				(width 0)
				(type default)
			)
			(fill no)
			(layer "F.Fab")
		)
		(pad "1" smd custom
			(at 0 -0.4445 180)
			(size 0.1397 0.1397)
			(layers "F.Cu" "F.Mask" "F.Paste")
			(net "PWRGD_P1V26_STBY")
			(options
				(clearance outline)
				(anchor circle)
			)
			(primitives
				(gr_poly
					(pts
						(arc
							(start -0.1778 -0.2794)
							(mid -0.249642 -0.249642)
							(end -0.2794 -0.1778)
						)
						(arc
							(start -0.2794 0.1778)
							(mid -0.249642 0.249642)
							(end -0.1778 0.2794)
						)
						(arc
							(start 0.1778 0.2794)
							(mid 0.249642 0.249642)
							(end 0.2794 0.1778)
						)
						(arc
							(start 0.2794 -0.1778)
							(mid 0.249642 -0.249642)
							(end 0.1778 -0.2794)
						)
					)
					(width 0)
					(fill yes)
				)
			)
		)
		(pad "2" smd custom
			(at 0 0.4445 180)
			(size 0.1397 0.1397)
			(layers "F.Cu" "F.Mask" "F.Paste")
			(net "U80_B")
			(options
				(clearance outline)
				(anchor circle)
			)
			(primitives
				(gr_poly
					(pts
						(arc
							(start -0.1778 -0.2794)
							(mid -0.249642 -0.249642)
							(end -0.2794 -0.1778)
						)
						(arc
							(start -0.2794 0.1778)
							(mid -0.249642 0.249642)
							(end -0.1778 0.2794)
						)
						(arc
							(start 0.1778 0.2794)
							(mid 0.249642 0.249642)
							(end 0.2794 0.1778)
						)
						(arc
							(start 0.2794 -0.1778)
							(mid 0.249642 -0.249642)
							(end 0.1778 -0.2794)
						)
					)
					(width 0)
					(fill yes)
				)
			)
		)
	)
)
